# BASEBOARD_FAB2 (Tioga Pass) — schematic netlist excerpt (pin names and nets, part order shuffled) for the footprints in the layout excerpt that follows; sources: Cadence DE-HDL packaged netlist, KiCad conversion of Wiwynn_Tioga_Pass_MB.brd

R9A4  RES  475.0 1% CHIP  pkg 0402  page 111 : A = CPU_XDP_PRESENT_N ; B = PVCCIO_CPU0
FB25W1  BLM15AG121SN-1GP  pkg DISCRET-G  page 254 : \1\ = XDP_CPU_TCK0_R ; \2\ = XDP_CPU_TCK0
R1D40  RES  40.2K 1% CHIP  pkg 0402  page 199 : A = A_HSC_PSET ; B = AGND_HSC

(kicad_pcb
	(version 20260206)
	(generator "pcbnew")
	(generator_version "10.0")
	(general
		(thickness 1.6)
		(legacy_teardrops no)
	)
	(paper "A4")
	(title_block
		(title "Wiwynn_Tioga_Pass_MB.brd")
		(comment 1 "Tioga Pass / footprints 284-286 of 4770")
	)
	(layers
		(0 "F.Cu" signal "TOP")
		(4 "In1.Cu" signal "L2GND")
		(6 "In2.Cu" signal "L3")
		(8 "In3.Cu" signal "L4GND")
		(10 "In4.Cu" signal "L5")
		(12 "In5.Cu" signal "L6GND")
		(14 "In6.Cu" signal "L7VCC")
		(16 "In7.Cu" signal "L8VCC")
		(18 "In8.Cu" signal "L9GND")
		(20 "In9.Cu" signal "L10")
		(22 "In10.Cu" signal "L11GND")
		(24 "In11.Cu" signal "L12")
		(26 "In12.Cu" signal "L13GND")
		(2 "B.Cu" signal "BOTTOM")
		(9 "F.Adhes" user "F.Adhesive")
		(11 "B.Adhes" user "B.Adhesive")
		(13 "F.Paste" user "Package Geometry/Pastemask Top")
		(15 "B.Paste" user "Package Geometry/Pastemask Bottom")
		(5 "F.SilkS" user "Ref Des/Silkscreen Top")
		(7 "B.SilkS" user "Ref Des/Silkscreen Bottom")
		(1 "F.Mask" user "Board Geometry/Soldermask Top")
		(3 "B.Mask" user "Board Geometry/Soldermask Bottom")
		(17 "Dwgs.User" user "User.Drawings")
		(19 "Cmts.User" user "User.Comments")
		(21 "Eco1.User" user "User.Eco1")
		(23 "Eco2.User" user "User.Eco2")
		(25 "Edge.Cuts" user "Board Geometry/Outline")
		(27 "Margin" user)
		(31 "F.CrtYd" user "Package Geometry/Place Bound Top")
		(29 "B.CrtYd" user "Package Geometry/Place Bound Bottom")
		(35 "F.Fab" user "Ref Des/Assembly Top")
		(33 "B.Fab" user "Ref Des/Assembly Bottom")
	)
	(footprint ""
		(layer "F.Cu")
		(at 22.225 -72.4662 90)
		(property "Reference" "R1D40"
			(at 0 0 90)
			(layer "F.SilkS")
			(hide yes)
			(effects
				(font
					(size 1.27 1.27)
				)
			)
		)
		(property "Value" ""
			(at 0 0 90)
			(layer "F.Fab")
			(effects
				(font
					(size 1.27 1.27)
				)
			)
		)
		(duplicate_pad_numbers_are_jumpers no)
		(fp_poly
			(pts
				(xy -0.2794 -0.1016) (xy 0.2794 -0.1016) (xy 0.2794 0.9906) (xy -0.2794 0.9906)
			)
			(stroke
				(width 0)
				(type default)
			)
			(fill no)
			(layer "F.CrtYd")
		)
		(fp_line
			(start 0.2794 -0.1016)
			(end -0.2794 -0.1016)
			(stroke
				(width 0.1)
				(type default)
			)
			(layer "F.Fab")
		)
		(fp_line
			(start -0.2794 -0.1016)
			(end -0.2794 0.9906)
			(stroke
				(width 0.1)
				(type default)
			)
			(layer "F.Fab")
		)
		(fp_line
			(start 0.2794 0.9906)
			(end 0.2794 -0.1016)
			(stroke
				(width 0.1)
				(type default)
			)
			(layer "F.Fab")
		)
		(fp_line
			(start -0.2794 0.9906)
			(end 0.2794 0.9906)
			(stroke
				(width 0.1)
				(type default)
			)
			(layer "F.Fab")
		)
		(pad "1" smd rect
			(at 0 0 90)
			(size 0.508 0.508)
			(layers "F.Cu" "F.Mask" "F.Paste")
			(net "A_HSC_PSET")
		)
		(pad "2" smd rect
			(at 0 0.889 90)
			(size 0.508 0.508)
			(layers "F.Cu" "F.Mask" "F.Paste")
			(net "AGND_HSC")
		)
		(zone
			(layer "F.Cu")
			(hatch none 0.5)
			(connect_pads
				(clearance 0)
			)
			(min_thickness 0.25)
			(keepout
				(tracks allowed)
				(vias not_allowed)
				(pads allowed)
				(copperpour not_allowed)
				(footprints allowed)
			)
			(placement
				(enabled no)
				(sheetname "")
			)
			(fill
				(thermal_gap 0.5)
				(thermal_bridge_width 0.5)
				(island_removal_mode 0)
			)
			(polygon
				(pts
					(xy 22.479 -72.2122) (xy 22.479 -72.7202) (xy 22.86 -72.7202) (xy 22.86 -72.2122)
				)
			)
		)
		(zone
			(layer "F.Cu")
			(hatch none 0.5)
			(connect_pads
				(clearance 0)
			)
			(min_thickness 0.25)
			(keepout
				(tracks not_allowed)
				(vias allowed)
				(pads allowed)
				(copperpour not_allowed)
				(footprints allowed)
			)
			(placement
				(enabled no)
				(sheetname "")
			)
			(fill
				(thermal_gap 0.5)
				(thermal_bridge_width 0.5)
				(island_removal_mode 0)
			)
			(polygon
				(pts
					(xy 22.86 -72.2122) (xy 22.86 -72.7202) (xy 22.479 -72.7202) (xy 22.479 -72.2122)
				)
			)
		)
	)
	(footprint ""
		(layer "F.Cu")
		(at 454.025 -150.241 180)
		(property "Reference" "R9A4"
			(at 0 0 180)
			(layer "F.SilkS")
			(hide yes)
			(effects
				(font
					(size 1.27 1.27)
				)
			)
		)
		(property "Value" ""
			(at 0 0 180)
			(layer "F.Fab")
			(effects
				(font
					(size 1.27 1.27)
				)
			)
		)
		(duplicate_pad_numbers_are_jumpers no)
		(fp_poly
			(pts
				(xy -0.2794 -0.1016) (xy 0.2794 -0.1016) (xy 0.2794 0.9906) (xy -0.2794 0.9906)
			)
			(stroke
				(width 0)
				(type default)
			)
			(fill no)
			(layer "F.CrtYd")
		)
		(fp_line
			(start 0.2794 0.9906)
			(end 0.2794 -0.1016)
			(stroke
				(width 0.1)
				(type default)
			)
			(layer "F.Fab")
		)
		(fp_line
			(start 0.2794 -0.1016)
			(end -0.2794 -0.1016)
			(stroke
				(width 0.1)
				(type default)
			)
			(layer "F.Fab")
		)
		(fp_line
			(start -0.2794 0.9906)
			(end 0.2794 0.9906)
			(stroke
				(width 0.1)
				(type default)
			)
			(layer "F.Fab")
		)
		(fp_line
			(start -0.2794 -0.1016)
			(end -0.2794 0.9906)
			(stroke
				(width 0.1)
				(type default)
			)
			(layer "F.Fab")
		)
		(pad "1" smd rect
			(at 0 0 180)
			(size 0.508 0.508)
			(layers "F.Cu" "F.Mask" "F.Paste")
			(net "CPU_XDP_PRESENT_N")
		)
		(pad "2" smd rect
			(at 0 0.889 180)
			(size 0.508 0.508)
			(layers "F.Cu" "F.Mask" "F.Paste")
			(net "PVCCIO_CPU0")
		)
		(zone
			(layer "F.Cu")
			(hatch none 0.5)
			(connect_pads
				(clearance 0)
			)
			(min_thickness 0.25)
			(keepout
				(tracks not_allowed)
				(vias allowed)
				(pads allowed)
				(copperpour not_allowed)
				(footprints allowed)
			)
			(placement
				(enabled no)
				(sheetname "")
			)
			(fill
				(thermal_gap 0.5)
				(thermal_bridge_width 0.5)
				(island_removal_mode 0)
			)
			(polygon
				(pts
					(xy 454.279 -150.876) (xy 453.771 -150.876) (xy 453.771 -150.495) (xy 454.279 -150.495)
				)
			)
		)
		(zone
			(layer "F.Cu")
			(hatch none 0.5)
			(connect_pads
				(clearance 0)
			)
			(min_thickness 0.25)
			(keepout
				(tracks allowed)
				(vias not_allowed)
				(pads allowed)
				(copperpour not_allowed)
				(footprints allowed)
			)
			(placement
				(enabled no)
				(sheetname "")
			)
			(fill
				(thermal_gap 0.5)
				(thermal_bridge_width 0.5)
				(island_removal_mode 0)
			)
			(polygon
				(pts
					(xy 454.279 -150.495) (xy 453.771 -150.495) (xy 453.771 -150.876) (xy 454.279 -150.876)
				)
			)
		)
	)
	(footprint ""
		(layer "F.Cu")
		(at 443.289944 -153.225246 90)
		(property "Reference" "FB25W1"
			(at 0 0 90)
			(layer "F.SilkS")
			(hide yes)
			(effects
				(font
					(size 1.27 1.27)
				)
			)
		)
		(property "Value" "*"
			(at -0.0127 -7.01675 90)
			(unlocked yes)
			(layer "F.Fab")
			(hide yes)
			(effects
				(font
					(size 0.889 0.889)
					(thickness 0.1524)
				)
			)
		)
		(property "Device Type" "BLM15AG121SN-1GP_DISCRET-G-BLMA"
			(at -0.0127 -8.54075 90)
			(unlocked yes)
			(layer "F.Fab")
			(hide yes)
			(effects
				(font
					(size 0.889 0.889)
					(thickness 0.1524)
				)
			)
		)
		(duplicate_pad_numbers_are_jumpers no)
		(fp_line
			(start 0.508 -0.9398)
			(end -0.508 -0.9398)
			(stroke
				(width 0.1524)
				(type default)
			)
			(layer "F.SilkS")
		)
		(fp_line
			(start -0.508 -0.9398)
			(end -0.508 0.9398)
			(stroke
				(width 0.1524)
				(type default)
			)
			(layer "F.SilkS")
		)
		(fp_line
			(start -0.508 0.9398)
			(end -0.508 0.8636)
			(stroke
				(width 0.1524)
				(type default)
			)
			(layer "F.SilkS")
		)
		(fp_rect
			(start -0.508 0.9398)
			(end 0.508 -0.9398)
			(stroke
				(width 0)
				(type default)
			)
			(fill no)
			(layer "F.CrtYd")
		)
		(fp_rect
			(start -0.508 0.9398)
			(end 0.508 -0.9398)
			(stroke
				(width 0)
				(type default)
			)
			(fill no)
			(layer "F.Fab")
		)
		(pad "1" smd custom
			(at 0 -0.4445 90)
			(size 0.1397 0.1397)
			(layers "F.Cu" "F.Mask" "F.Paste")
			(net "XDP_CPU_TCK0_R")
			(options
				(clearance outline)
				(anchor circle)
			)
			(primitives
				(gr_poly
					(pts
						(arc
							(start -0.1778 -0.2794)
							(mid -0.249642 -0.249642)
							(end -0.2794 -0.1778)
						)
						(arc
							(start -0.2794 0.1778)
							(mid -0.249642 0.249642)
							(end -0.1778 0.2794)
						)
						(arc
							(start 0.1778 0.2794)
							(mid 0.249642 0.249642)
							(end 0.2794 0.1778)
						)
						(arc
							(start 0.2794 -0.1778)
							(mid 0.249642 -0.249642)
							(end 0.1778 -0.2794)
						)
					)
					(width 0)
					(fill yes)
				)
			)
		)
		(pad "2" smd custom
			(at 0 0.4445 90)
			(size 0.1397 0.1397)
			(layers "F.Cu" "F.Mask" "F.Paste")
			(net "XDP_CPU_TCK0")
			(options
				(clearance outline)
				(anchor circle)
			)
			(primitives
				(gr_poly
					(pts
						(arc
							(start -0.1778 -0.2794)
							(mid -0.249642 -0.249642)
							(end -0.2794 -0.1778)
						)
						(arc
							(start -0.2794 0.1778)
							(mid -0.249642 0.249642)
							(end -0.1778 0.2794)
						)
						(arc
							(start 0.1778 0.2794)
							(mid 0.249642 0.249642)
							(end 0.2794 0.1778)
						)
						(arc
							(start 0.2794 -0.1778)
							(mid 0.249642 -0.249642)
							(end 0.1778 -0.2794)
						)
					)
					(width 0)
					(fill yes)
				)
			)
		)
	)
)
